(kicad_pcb
	(version 20260206)
	(generator "pcbnew")
	(generator_version "10.0")
	(general
		(thickness 1.6)
		(legacy_teardrops no)
	)
	(paper "A4")
	(title_block
		(title "peb — Lightning_PEB_BRD.brd")
		(comment 1 "Lightning (Wiwynn / Facebook NVMe JBOF) / footprints 2108-2115 of 2563")
	)
	(layers
		(0 "F.Cu" signal "TOP")
		(4 "In1.Cu" signal "L2GND")
		(6 "In2.Cu" signal "L3")
		(8 "In3.Cu" signal "L4VCC")
		(10 "In4.Cu" signal "L5VCC")
		(12 "In5.Cu" signal "L6")
		(14 "In6.Cu" signal "L7GND")
		(2 "B.Cu" signal "BOTTOM")
		(9 "F.Adhes" user "F.Adhesive")
		(11 "B.Adhes" user "B.Adhesive")
		(13 "F.Paste" user "Package Geometry/Pastemask Top")
		(15 "B.Paste" user "Package Geometry/Pastemask Bottom")
		(5 "F.SilkS" user "Ref Des/Silkscreen Top")
		(7 "B.SilkS" user "Ref Des/Silkscreen Bottom")
		(1 "F.Mask" user "Board Geometry/Soldermask Top")
		(3 "B.Mask" user "Board Geometry/Soldermask Bottom")
		(17 "Dwgs.User" user "User.Drawings")
		(19 "Cmts.User" user "User.Comments")
		(21 "Eco1.User" user "User.Eco1")
		(23 "Eco2.User" user "User.Eco2")
		(25 "Edge.Cuts" user "Board Geometry/Outline")
		(27 "Margin" user)
		(31 "F.CrtYd" user "Package Geometry/Place Bound Top")
		(29 "B.CrtYd" user "Package Geometry/Place Bound Bottom")
		(35 "F.Fab" user "Ref Des/Assembly Top")
		(33 "B.Fab" user "Ref Des/Assembly Bottom")
	)
	(footprint ""
		(layer "B.Cu")
		(at 53.721 -139.827 90)
		(property "Reference" "SR852"
			(at 0 0 90)
			(layer "B.SilkS")
			(hide yes)
			(effects
				(font
					(size 1.27 1.27)
				)
				(justify mirror)
			)
		)
		(property "Value" "4K75R2F-1-GP"
			(at -0.064008 -3.993896 90)
			(unlocked yes)
			(layer "B.Fab")
			(hide yes)
			(effects
				(font
					(size 1.016 1.016)
					(thickness 0.1524)
				)
				(justify mirror)
			)
		)
		(property "Device Type" "R402H16"
			(at -0.064008 -5.517896 90)
			(unlocked yes)
			(layer "B.Fab")
			(hide yes)
			(effects
				(font
					(size 1.016 1.016)
					(thickness 0.1524)
				)
				(justify mirror)
			)
		)
		(duplicate_pad_numbers_are_jumpers no)
		(fp_line
			(start 0.508 -0.9398)
			(end 0.508 0.9398)
			(stroke
				(width 0.1524)
				(type default)
			)
			(layer "B.SilkS")
		)
		(fp_line
			(start -0.508 -0.9398)
			(end 0.508 -0.9398)
			(stroke
				(width 0.1524)
				(type default)
			)
			(layer "B.SilkS")
		)
		(fp_rect
			(start 0.508 0.9398)
			(end -0.508 -0.9398)
			(stroke
				(width 0)
				(type default)
			)
			(fill no)
			(layer "B.CrtYd")
		)
		(fp_rect
			(start 0.508 0.9398)
			(end -0.508 -0.9398)
			(stroke
				(width 0)
				(type default)
			)
			(fill no)
			(layer "B.Fab")
		)
		(pad "1" smd custom
			(at 0 -0.4445 270)
			(size 0.1397 0.1397)
			(layers "B.Cu" "B.Mask" "B.Paste")
			(net "BMC_FW_DET_BOARD_VER_0")
			(options
				(clearance outline)
				(anchor circle)
			)
			(primitives
				(gr_poly
					(pts
						(arc
							(start -0.1778 0.2794)
							(mid -0.249642 0.249642)
							(end -0.2794 0.1778)
						)
						(arc
							(start -0.2794 -0.1778)
							(mid -0.249642 -0.249642)
							(end -0.1778 -0.2794)
						)
						(arc
							(start 0.1778 -0.2794)
							(mid 0.249642 -0.249642)
							(end 0.2794 -0.1778)
						)
						(arc
							(start 0.2794 0.1778)
							(mid 0.249642 0.249642)
							(end 0.1778 0.2794)
						)
					)
					(width 0)
					(fill yes)
				)
			)
		)
		(pad "2" smd custom
			(at 0 0.4445 270)
			(size 0.1397 0.1397)
			(layers "B.Cu" "B.Mask" "B.Paste")
			(net "GND")
			(options
				(clearance outline)
				(anchor circle)
			)
			(primitives
				(gr_poly
					(pts
						(arc
							(start -0.1778 0.2794)
							(mid -0.249642 0.249642)
							(end -0.2794 0.1778)
						)
						(arc
							(start -0.2794 -0.1778)
							(mid -0.249642 -0.249642)
							(end -0.1778 -0.2794)
						)
						(arc
							(start 0.1778 -0.2794)
							(mid 0.249642 -0.249642)
							(end 0.2794 -0.1778)
						)
						(arc
							(start 0.2794 0.1778)
							(mid 0.249642 0.249642)
							(end 0.1778 0.2794)
						)
					)
					(width 0)
					(fill yes)
				)
			)
		)
	)
	(footprint ""
		(layer "B.Cu")
		(at 239.1664 -54.0004 90)
		(property "Reference" "C27"
			(at 0 0 90)
			(layer "B.SilkS")
			(hide yes)
			(effects
				(font
					(size 1.27 1.27)
				)
				(justify mirror)
			)
		)
		(property "Value" "SCD1U16V1KX-1-GP"
			(at 2.8321 -1.7399 90)
			(unlocked yes)
			(layer "B.Fab")
			(hide yes)
			(effects
				(font
					(size 1.016 1.016)
					(thickness 0.1524)
				)
				(justify mirror)
			)
		)
		(property "Device Type" "C0201H13"
			(at 2.8321 -3.2639 90)
			(unlocked yes)
			(layer "B.Fab")
			(hide yes)
			(effects
				(font
					(size 1.016 1.016)
					(thickness 0.1524)
				)
				(justify mirror)
			)
		)
		(duplicate_pad_numbers_are_jumpers no)
		(fp_rect
			(start 0.2794 0.6477)
			(end -0.2794 -0.6477)
			(stroke
				(width 0)
				(type default)
			)
			(fill no)
			(layer "B.CrtYd")
		)
		(fp_rect
			(start 0.2794 0.6477)
			(end -0.2794 -0.6477)
			(stroke
				(width 0)
				(type default)
			)
			(fill no)
			(layer "B.Fab")
		)
		(pad "1" smd custom
			(at 0 -0.2794 270)
			(size 0.0762 0.0762)
			(layers "B.Cu" "B.Mask" "B.Paste")
			(net "DUT_VDD")
			(options
				(clearance outline)
				(anchor circle)
			)
			(primitives
				(gr_poly
					(pts
						(arc
							(start 0.1524 0.127)
							(mid 0.137521 0.162921)
							(end 0.1016 0.1778)
						)
						(arc
							(start -0.1016 0.1778)
							(mid -0.137521 0.162921)
							(end -0.1524 0.127)
						)
						(arc
							(start -0.1524 -0.127)
							(mid -0.137521 -0.162921)
							(end -0.1016 -0.1778)
						)
						(arc
							(start 0.1016 -0.1778)
							(mid 0.137521 -0.162921)
							(end 0.1524 -0.127)
						)
					)
					(width 0)
					(fill yes)
				)
			)
		)
		(pad "2" smd custom
			(at 0 0.2794 270)
			(size 0.0762 0.0762)
			(layers "B.Cu" "B.Mask" "B.Paste")
			(net "GND")
			(options
				(clearance outline)
				(anchor circle)
			)
			(primitives
				(gr_poly
					(pts
						(arc
							(start 0.1524 0.127)
							(mid 0.137521 0.162921)
							(end 0.1016 0.1778)
						)
						(arc
							(start -0.1016 0.1778)
							(mid -0.137521 0.162921)
							(end -0.1524 0.127)
						)
						(arc
							(start -0.1524 -0.127)
							(mid -0.137521 -0.162921)
							(end -0.1016 -0.1778)
						)
						(arc
							(start 0.1016 -0.1778)
							(mid 0.137521 -0.162921)
							(end 0.1524 -0.127)
						)
					)
					(width 0)
					(fill yes)
				)
			)
		)
	)
	(footprint ""
		(layer "B.Cu")
		(at 165.0492 -200.2028 -90)
		(property "Reference" "C4116"
			(at 0 0 90)
			(layer "B.SilkS")
			(hide yes)
			(effects
				(font
					(size 1.27 1.27)
				)
				(justify mirror)
			)
		)
		(property "Value" "SCD1U25V3KX-GP"
			(at 0 -2.8194 270)
			(unlocked yes)
			(layer "B.Fab")
			(hide yes)
			(effects
				(font
					(size 1.016 1.016)
					(thickness 0.1524)
				)
				(justify mirror)
			)
		)
		(property "Device Type" "C603H36"
			(at 0 -4.3434 270)
			(unlocked yes)
			(layer "B.Fab")
			(hide yes)
			(effects
				(font
					(size 1.016 1.016)
					(thickness 0.1524)
				)
				(justify mirror)
			)
		)
		(duplicate_pad_numbers_are_jumpers no)
		(fp_line
			(start -0.508 0)
			(end 0.508 0)
			(stroke
				(width 0.2032)
				(type default)
			)
			(layer "B.SilkS")
		)
		(fp_rect
			(start 0.5842 1.3335)
			(end -0.5842 -1.3335)
			(stroke
				(width 0)
				(type default)
			)
			(fill no)
			(layer "B.CrtYd")
		)
		(fp_rect
			(start 0.5842 1.3335)
			(end -0.5842 -1.3335)
			(stroke
				(width 0)
				(type default)
			)
			(fill no)
			(layer "B.Fab")
		)
		(pad "1" smd custom
			(at 0 -0.762 90)
			(size 0.2159 0.2159)
			(layers "B.Cu" "B.Mask" "B.Paste")
			(net "GND")
			(options
				(clearance outline)
				(anchor circle)
			)
			(primitives
				(gr_poly
					(pts
						(arc
							(start -0.3302 0.4318)
							(mid -0.402042 0.402042)
							(end -0.4318 0.3302)
						)
						(arc
							(start -0.4318 -0.3302)
							(mid -0.402042 -0.402042)
							(end -0.3302 -0.4318)
						)
						(arc
							(start 0.3302 -0.4318)
							(mid 0.402042 -0.402042)
							(end 0.4318 -0.3302)
						)
						(arc
							(start 0.4318 0.3302)
							(mid 0.402042 0.402042)
							(end 0.3302 0.4318)
						)
					)
					(width 0)
					(fill yes)
				)
			)
		)
		(pad "2" smd custom
			(at 0 0.762 90)
			(size 0.2159 0.2159)
			(layers "B.Cu" "B.Mask" "B.Paste")
			(net "SSD_PWREN11_R")
			(options
				(clearance outline)
				(anchor circle)
			)
			(primitives
				(gr_poly
					(pts
						(arc
							(start -0.3302 0.4318)
							(mid -0.402042 0.402042)
							(end -0.4318 0.3302)
						)
						(arc
							(start -0.4318 -0.3302)
							(mid -0.402042 -0.402042)
							(end -0.3302 -0.4318)
						)
						(arc
							(start 0.3302 -0.4318)
							(mid 0.402042 -0.402042)
							(end 0.4318 -0.3302)
						)
						(arc
							(start 0.4318 0.3302)
							(mid 0.402042 0.402042)
							(end 0.3302 0.4318)
						)
					)
					(width 0)
					(fill yes)
				)
			)
		)
	)
	(footprint ""
		(layer "B.Cu")
		(at 52.965604 -113.83391 -90)
		(property "Reference" "R437"
			(at 0 0 90)
			(layer "B.SilkS")
			(hide yes)
			(effects
				(font
					(size 1.27 1.27)
				)
				(justify mirror)
			)
		)
		(property "Value" "4K7R2F-GP"
			(at -0.064008 -3.993896 270)
			(unlocked yes)
			(layer "B.Fab")
			(hide yes)
			(effects
				(font
					(size 1.016 1.016)
					(thickness 0.1524)
				)
				(justify mirror)
			)
		)
		(property "Device Type" "R402H16"
			(at -0.064008 -5.517896 270)
			(unlocked yes)
			(layer "B.Fab")
			(hide yes)
			(effects
				(font
					(size 1.016 1.016)
					(thickness 0.1524)
				)
				(justify mirror)
			)
		)
		(duplicate_pad_numbers_are_jumpers no)
		(fp_line
			(start -0.508 -0.9398)
			(end 0.508 -0.9398)
			(stroke
				(width 0.1524)
				(type default)
			)
			(layer "B.SilkS")
		)
		(fp_line
			(start 0.508 -0.9398)
			(end 0.508 0.9398)
			(stroke
				(width 0.1524)
				(type default)
			)
			(layer "B.SilkS")
		)
		(fp_rect
			(start 0.508 0.9398)
			(end -0.508 -0.9398)
			(stroke
				(width 0)
				(type default)
			)
			(fill no)
			(layer "B.CrtYd")
		)
		(fp_rect
			(start 0.508 0.9398)
			(end -0.508 -0.9398)
			(stroke
				(width 0)
				(type default)
			)
			(fill no)
			(layer "B.Fab")
		)
		(pad "1" smd custom
			(at 0 -0.4445 90)
			(size 0.1397 0.1397)
			(layers "B.Cu" "B.Mask" "B.Paste")
			(net "BMC_I2C12_MINI6_SCL_S")
			(options
				(clearance outline)
				(anchor circle)
			)
			(primitives
				(gr_poly
					(pts
						(arc
							(start -0.1778 0.2794)
							(mid -0.249642 0.249642)
							(end -0.2794 0.1778)
						)
						(arc
							(start -0.2794 -0.1778)
							(mid -0.249642 -0.249642)
							(end -0.1778 -0.2794)
						)
						(arc
							(start 0.1778 -0.2794)
							(mid 0.249642 -0.249642)
							(end 0.2794 -0.1778)
						)
						(arc
							(start 0.2794 0.1778)
							(mid 0.249642 0.249642)
							(end 0.1778 0.2794)
						)
					)
					(width 0)
					(fill yes)
				)
			)
		)
		(pad "2" smd custom
			(at 0 0.4445 90)
			(size 0.1397 0.1397)
			(layers "B.Cu" "B.Mask" "B.Paste")
			(net "P3V3_STBY")
			(options
				(clearance outline)
				(anchor circle)
			)
			(primitives
				(gr_poly
					(pts
						(arc
							(start -0.1778 0.2794)
							(mid -0.249642 0.249642)
							(end -0.2794 0.1778)
						)
						(arc
							(start -0.2794 -0.1778)
							(mid -0.249642 -0.249642)
							(end -0.1778 -0.2794)
						)
						(arc
							(start 0.1778 -0.2794)
							(mid 0.249642 -0.249642)
							(end 0.2794 -0.1778)
						)
						(arc
							(start 0.2794 0.1778)
							(mid 0.249642 0.249642)
							(end 0.1778 0.2794)
						)
					)
					(width 0)
					(fill yes)
				)
			)
		)
	)
	(footprint ""
		(layer "B.Cu")
		(at 70.993 -192.532)
		(property "Reference" "R3234"
			(at 0 0 0)
			(layer "B.SilkS")
			(hide yes)
			(effects
				(font
					(size 1.27 1.27)
				)
				(justify mirror)
			)
		)
		(property "Value" "0R2J-2-GP"
			(at -0.064008 -3.993896 0)
			(unlocked yes)
			(layer "B.Fab")
			(hide yes)
			(effects
				(font
					(size 1.016 1.016)
					(thickness 0.1524)
				)
				(justify mirror)
			)
		)
		(property "Device Type" "R402H16"
			(at -0.064008 -5.517896 0)
			(unlocked yes)
			(layer "B.Fab")
			(hide yes)
			(effects
				(font
					(size 1.016 1.016)
					(thickness 0.1524)
				)
				(justify mirror)
			)
		)
		(duplicate_pad_numbers_are_jumpers no)
		(fp_line
			(start -0.508 -0.9398)
			(end 0.508 -0.9398)
			(stroke
				(width 0.1524)
				(type default)
			)
			(layer "B.SilkS")
		)
		(fp_line
			(start 0.508 -0.9398)
			(end 0.508 0.9398)
			(stroke
				(width 0.1524)
				(type default)
			)
			(layer "B.SilkS")
		)
		(fp_rect
			(start 0.508 0.9398)
			(end -0.508 -0.9398)
			(stroke
				(width 0)
				(type default)
			)
			(fill no)
			(layer "B.CrtYd")
		)
		(fp_rect
			(start 0.508 0.9398)
			(end -0.508 -0.9398)
			(stroke
				(width 0)
				(type default)
			)
			(fill no)
			(layer "B.Fab")
		)
		(pad "1" smd custom
			(at 0 -0.4445 180)
			(size 0.1397 0.1397)
			(layers "B.Cu" "B.Mask" "B.Paste")
			(net "SSD_PERST#11")
			(options
				(clearance outline)
				(anchor circle)
			)
			(primitives
				(gr_poly
					(pts
						(arc
							(start -0.1778 0.2794)
							(mid -0.249642 0.249642)
							(end -0.2794 0.1778)
						)
						(arc
							(start -0.2794 -0.1778)
							(mid -0.249642 -0.249642)
							(end -0.1778 -0.2794)
						)
						(arc
							(start 0.1778 -0.2794)
							(mid 0.249642 -0.249642)
							(end 0.2794 -0.1778)
						)
						(arc
							(start 0.2794 0.1778)
							(mid 0.249642 0.249642)
							(end 0.1778 0.2794)
						)
					)
					(width 0)
					(fill yes)
				)
			)
		)
		(pad "2" smd custom
			(at 0 0.4445 180)
			(size 0.1397 0.1397)
			(layers "B.Cu" "B.Mask" "B.Paste")
			(net "SSD_PERST#0_B11")
			(options
				(clearance outline)
				(anchor circle)
			)
			(primitives
				(gr_poly
					(pts
						(arc
							(start -0.1778 0.2794)
							(mid -0.249642 0.249642)
							(end -0.2794 0.1778)
						)
						(arc
							(start -0.2794 -0.1778)
							(mid -0.249642 -0.249642)
							(end -0.1778 -0.2794)
						)
						(arc
							(start 0.1778 -0.2794)
							(mid 0.249642 -0.249642)
							(end 0.2794 -0.1778)
						)
						(arc
							(start 0.2794 0.1778)
							(mid 0.249642 0.249642)
							(end 0.1778 0.2794)
						)
					)
					(width 0)
					(fill yes)
				)
			)
		)
	)
	(footprint ""
		(layer "B.Cu")
		(at 25.86228 -78.00848 90)
		(property "Reference" "C625"
			(at 0 0 90)
			(layer "B.SilkS")
			(hide yes)
			(effects
				(font
					(size 1.27 1.27)
				)
				(justify mirror)
			)
		)
		(property "Value" "SC47U6D3V5MX-1-GP"
			(at 0.0762 -6.1214 90)
			(unlocked yes)
			(layer "B.Fab")
			(hide yes)
			(effects
				(font
					(size 1.016 1.016)
					(thickness 0.1524)
				)
				(justify mirror)
			)
		)
		(property "Device Type" "C805H54"
			(at 0.0762 -8.1534 90)
			(unlocked yes)
			(layer "B.Fab")
			(hide yes)
			(effects
				(font
					(size 1.016 1.016)
					(thickness 0.1524)
				)
				(justify mirror)
			)
		)
		(duplicate_pad_numbers_are_jumpers no)
		(fp_line
			(start -0.635 0)
			(end 0.635 0)
			(stroke
				(width 0.508)
				(type default)
			)
			(layer "B.SilkS")
		)
		(fp_rect
			(start 0.9652 1.778)
			(end -0.9652 -1.778)
			(stroke
				(width 0)
				(type default)
			)
			(fill no)
			(layer "B.CrtYd")
		)
		(fp_poly
			(pts
				(xy 0.9652 -1.778) (xy -0.9652 -1.778) (xy -0.9652 1.778) (xy 0.9652 1.778)
			)
			(stroke
				(width 0)
				(type default)
			)
			(fill no)
			(layer "B.Fab")
		)
		(pad "1" smd rect
			(at 0 -0.9652 270)
			(size 1.397 1.143)
			(layers "B.Cu" "B.Mask" "B.Paste")
			(net "P3V3_STBY")
		)
		(pad "2" smd rect
			(at 0 0.9652 270)
			(size 1.397 1.143)
			(layers "B.Cu" "B.Mask" "B.Paste")
			(net "GND")
		)
	)
	(footprint ""
		(layer "B.Cu")
		(at 46.228 -118.364)
		(property "Reference" "TP155"
			(at 0 0 0)
			(layer "B.SilkS")
			(hide yes)
			(effects
				(font
					(size 1.27 1.27)
				)
				(justify mirror)
			)
		)
		(property "Value" "TPAD28-2-GP"
			(at 0.0127 -1.6637 0)
			(unlocked yes)
			(layer "B.Fab")
			(hide yes)
			(effects
				(font
					(size 1.016 1.016)
					(thickness 0.1524)
				)
				(justify mirror)
			)
		)
		(property "Device Type" "TPAD28"
			(at 0.0127 -3.1877 0)
			(unlocked yes)
			(layer "B.Fab")
			(hide yes)
			(effects
				(font
					(size 1.016 1.016)
					(thickness 0.1524)
				)
				(justify mirror)
			)
		)
		(duplicate_pad_numbers_are_jumpers no)
		(fp_poly
			(pts
				(arc
					(start 0.3556 0)
					(mid -0.3556 0)
					(end 0.3556 0)
				)
			)
			(stroke
				(width 0)
				(type default)
			)
			(fill no)
			(layer "B.CrtYd")
		)
		(fp_poly
			(pts
				(arc
					(start 0.6096 0)
					(mid -0.6096 0)
					(end 0.6096 0)
				)
			)
			(stroke
				(width 0)
				(type default)
			)
			(fill no)
			(layer "B.Fab")
		)
		(pad "1" smd circle
			(at 0 0 180)
			(size 0.7112 0.7112)
			(layers "B.Cu" "B.Mask" "B.Paste")
			(net "TP_GPIOA7")
		)
	)
	(footprint ""
		(layer "B.Cu")
		(at 238.6203 -40.005 90)
		(property "Reference" "C482"
			(at 0 0 90)
			(layer "B.SilkS")
			(hide yes)
			(effects
				(font
					(size 1.27 1.27)
				)
				(justify mirror)
			)
		)
		(property "Value" "SCD1U16V1KX-1-GP"
			(at 2.8321 -1.7399 90)
			(unlocked yes)
			(layer "B.Fab")
			(hide yes)
			(effects
				(font
					(size 1.016 1.016)
					(thickness 0.1524)
				)
				(justify mirror)
			)
		)
		(property "Device Type" "C0201H13"
			(at 2.8321 -3.2639 90)
			(unlocked yes)
			(layer "B.Fab")
			(hide yes)
			(effects
				(font
					(size 1.016 1.016)
					(thickness 0.1524)
				)
				(justify mirror)
			)
		)
		(duplicate_pad_numbers_are_jumpers no)
		(fp_rect
			(start 0.2794 0.6477)
			(end -0.2794 -0.6477)
			(stroke
				(width 0)
				(type default)
			)
			(fill no)
			(layer "B.CrtYd")
		)
		(fp_rect
			(start 0.2794 0.6477)
			(end -0.2794 -0.6477)
			(stroke
				(width 0)
				(type default)
			)
			(fill no)
			(layer "B.Fab")
		)
		(pad "1" smd custom
			(at 0 -0.2794 270)
			(size 0.0762 0.0762)
			(layers "B.Cu" "B.Mask" "B.Paste")
			(net "DUT_VDDO")
			(options
				(clearance outline)
				(anchor circle)
			)
			(primitives
				(gr_poly
					(pts
						(arc
							(start 0.1524 0.127)
							(mid 0.137521 0.162921)
							(end 0.1016 0.1778)
						)
						(arc
							(start -0.1016 0.1778)
							(mid -0.137521 0.162921)
							(end -0.1524 0.127)
						)
						(arc
							(start -0.1524 -0.127)
							(mid -0.137521 -0.162921)
							(end -0.1016 -0.1778)
						)
						(arc
							(start 0.1016 -0.1778)
							(mid 0.137521 -0.162921)
							(end 0.1524 -0.127)
						)
					)
					(width 0)
					(fill yes)
				)
			)
		)
		(pad "2" smd custom
			(at 0 0.2794 270)
			(size 0.0762 0.0762)
			(layers "B.Cu" "B.Mask" "B.Paste")
			(net "GND")
			(options
				(clearance outline)
				(anchor circle)
			)
			(primitives
				(gr_poly
					(pts
						(arc
							(start 0.1524 0.127)
							(mid 0.137521 0.162921)
							(end 0.1016 0.1778)
						)
						(arc
							(start -0.1016 0.1778)
							(mid -0.137521 0.162921)
							(end -0.1524 0.127)
						)
						(arc
							(start -0.1524 -0.127)
							(mid -0.137521 -0.162921)
							(end -0.1016 -0.1778)
						)
						(arc
							(start 0.1016 -0.1778)
							(mid 0.137521 -0.162921)
							(end 0.1524 -0.127)
						)
					)
					(width 0)
					(fill yes)
				)
			)
		)
	)
)
